# S9S_MB_2U (Grand Teton) — schematic netlist excerpt (pin names and nets, part order shuffled) for the footprints in the layout excerpt that follows; sources: Cadence DE-HDL packaged netlist, KiCad conversion of 03242023_DA0F0TMBIJ0_F0T_Motherboard_J_brd_V01_OCP.brd

R4108  Q_RES  10K 1% CHIP  pkg 0402LF  page 184 : A = PD_GPP_I_16 ; B = GND
PR375  Q_RES  1 1% CHIP  pkg 0402LF  page 278 : A = PVCCD_HV_CPU0_VCC ; B = P3V3_AUX

(kicad_pcb
	(version 20260206)
	(generator "pcbnew")
	(generator_version "10.0")
	(general
		(thickness 1.6)
		(legacy_teardrops no)
	)
	(paper "A4")
	(title_block
		(title "03242023_DA0F0TMBIJ0_F0T_Motherboard_J_brd_V01_OCP.brd")
		(comment 1 "Grand Teton / footprints 4784-4785 of 6105")
	)
	(layers
		(0 "F.Cu" signal "TOP")
		(4 "In1.Cu" signal "GND")
		(6 "In2.Cu" signal "IN1")
		(8 "In3.Cu" signal "GND1")
		(10 "In4.Cu" signal "IN2")
		(12 "In5.Cu" signal "GND2")
		(14 "In6.Cu" signal "IN3")
		(16 "In7.Cu" signal "GND3")
		(18 "In8.Cu" signal "VCC")
		(20 "In9.Cu" signal "VCC1")
		(22 "In10.Cu" signal "GND4")
		(24 "In11.Cu" signal "IN4")
		(26 "In12.Cu" signal "GND5")
		(28 "In13.Cu" signal "IN5")
		(30 "In14.Cu" signal "GND6")
		(32 "In15.Cu" signal "IN6")
		(34 "In16.Cu" signal "GND7")
		(2 "B.Cu" signal "BOTTOM")
		(9 "F.Adhes" user "F.Adhesive")
		(11 "B.Adhes" user "B.Adhesive")
		(13 "F.Paste" user "Package Geometry/Pastemask Top")
		(15 "B.Paste" user "Package Geometry/Pastemask Bottom")
		(5 "F.SilkS" user "Ref Des/Silkscreen Top")
		(7 "B.SilkS" user "Ref Des/Silkscreen Bottom")
		(1 "F.Mask" user "Board Geometry/Soldermask Top")
		(3 "B.Mask" user "Board Geometry/Soldermask Bottom")
		(17 "Dwgs.User" user "User.Drawings")
		(19 "Cmts.User" user "User.Comments")
		(21 "Eco1.User" user "User.Eco1")
		(23 "Eco2.User" user "User.Eco2")
		(25 "Edge.Cuts" user "Board Geometry/Outline")
		(27 "Margin" user)
		(31 "F.CrtYd" user "Package Geometry/Place Bound Top")
		(29 "B.CrtYd" user "Package Geometry/Place Bound Bottom")
		(35 "F.Fab" user "Ref Des/Assembly Top")
		(33 "B.Fab" user "Ref Des/Assembly Bottom")
	)
	(footprint ""
		(layer "B.Cu")
		(at 428.669958 -118.6053)
		(property "Reference" "PR375"
			(at 0 0 0)
			(layer "B.SilkS")
			(hide yes)
			(effects
				(font
					(size 1.27 1.27)
				)
				(justify mirror)
			)
		)
		(property "Value" ""
			(at 0 0 0)
			(layer "B.Fab")
			(effects
				(font
					(size 1.27 1.27)
				)
				(justify mirror)
			)
		)
		(duplicate_pad_numbers_are_jumpers no)
		(fp_line
			(start -0.7874 -0.4064)
			(end -0.7874 0.4064)
			(stroke
				(width 0.1524)
				(type default)
			)
			(layer "B.SilkS")
		)
		(fp_line
			(start -0.7874 0.4064)
			(end 0.7874 0.4064)
			(stroke
				(width 0.1524)
				(type default)
			)
			(layer "B.SilkS")
		)
		(fp_line
			(start 0.7874 -0.4064)
			(end -0.7874 -0.4064)
			(stroke
				(width 0.1524)
				(type default)
			)
			(layer "B.SilkS")
		)
		(fp_line
			(start 0.7874 0.4064)
			(end 0.7874 -0.4064)
			(stroke
				(width 0.1524)
				(type default)
			)
			(layer "B.SilkS")
		)
		(fp_line
			(start -0.67945 -0.3048)
			(end -0.67945 0.3048)
			(stroke
				(width 0.1)
				(type default)
			)
			(layer "B.Fab")
		)
		(fp_line
			(start -0.67945 0.3048)
			(end -0.120396 0.3048)
			(stroke
				(width 0.1)
				(type default)
			)
			(layer "B.Fab")
		)
		(fp_line
			(start -0.12065 -0.3048)
			(end -0.67945 -0.3048)
			(stroke
				(width 0.1)
				(type default)
			)
			(layer "B.Fab")
		)
		(fp_line
			(start -0.12065 -0.2794)
			(end -0.12065 -0.3048)
			(stroke
				(width 0.1)
				(type default)
			)
			(layer "B.Fab")
		)
		(fp_line
			(start -0.120396 0.2794)
			(end 0.12065 0.2794)
			(stroke
				(width 0.1)
				(type default)
			)
			(layer "B.Fab")
		)
		(fp_line
			(start -0.120396 0.3048)
			(end -0.120396 0.2794)
			(stroke
				(width 0.1)
				(type default)
			)
			(layer "B.Fab")
		)
		(fp_line
			(start 0.12065 -0.305054)
			(end 0.12065 -0.2794)
			(stroke
				(width 0.1)
				(type default)
			)
			(layer "B.Fab")
		)
		(fp_line
			(start 0.12065 -0.2794)
			(end -0.12065 -0.2794)
			(stroke
				(width 0.1)
				(type default)
			)
			(layer "B.Fab")
		)
		(fp_line
			(start 0.12065 0.2794)
			(end 0.12065 0.3048)
			(stroke
				(width 0.1)
				(type default)
			)
			(layer "B.Fab")
		)
		(fp_line
			(start 0.12065 0.3048)
			(end 0.67945 0.3048)
			(stroke
				(width 0.1)
				(type default)
			)
			(layer "B.Fab")
		)
		(fp_line
			(start 0.67945 -0.305054)
			(end 0.12065 -0.305054)
			(stroke
				(width 0.1)
				(type default)
			)
			(layer "B.Fab")
		)
		(fp_line
			(start 0.67945 0.3048)
			(end 0.67945 -0.305054)
			(stroke
				(width 0.1)
				(type default)
			)
			(layer "B.Fab")
		)
		(pad "1" smd circle
			(at 0.40005 0 180)
			(size 0 0)
			(layers "B.Cu" "B.Mask" "B.Paste")
			(net "PVCCD_HV_CPU0_VCC")
		)
		(pad "2" smd circle
			(at -0.40005 0 180)
			(size 0 0)
			(layers "B.Cu" "B.Mask" "B.Paste")
			(net "P3V3_AUX")
		)
	)
	(footprint ""
		(layer "B.Cu")
		(at 315.110622 -53.203348)
		(property "Reference" "R4108"
			(at 0 0 0)
			(layer "B.SilkS")
			(hide yes)
			(effects
				(font
					(size 1.27 1.27)
				)
				(justify mirror)
			)
		)
		(property "Value" ""
			(at 0 0 0)
			(layer "B.Fab")
			(effects
				(font
					(size 1.27 1.27)
				)
				(justify mirror)
			)
		)
		(duplicate_pad_numbers_are_jumpers no)
		(fp_line
			(start -0.7874 -0.4064)
			(end -0.7874 0.4064)
			(stroke
				(width 0.1524)
				(type default)
			)
			(layer "B.SilkS")
		)
		(fp_line
			(start -0.7874 0.4064)
			(end 0.7874 0.4064)
			(stroke
				(width 0.1524)
				(type default)
			)
			(layer "B.SilkS")
		)
		(fp_line
			(start 0.7874 -0.4064)
			(end -0.7874 -0.4064)
			(stroke
				(width 0.1524)
				(type default)
			)
			(layer "B.SilkS")
		)
		(fp_line
			(start 0.7874 0.4064)
			(end 0.7874 -0.4064)
			(stroke
				(width 0.1524)
				(type default)
			)
			(layer "B.SilkS")
		)
		(fp_line
			(start -0.67945 -0.3048)
			(end -0.67945 0.3048)
			(stroke
				(width 0.1)
				(type default)
			)
			(layer "B.Fab")
		)
		(fp_line
			(start -0.67945 0.3048)
			(end -0.120396 0.3048)
			(stroke
				(width 0.1)
				(type default)
			)
			(layer "B.Fab")
		)
		(fp_line
			(start -0.12065 -0.3048)
			(end -0.67945 -0.3048)
			(stroke
				(width 0.1)
				(type default)
			)
			(layer "B.Fab")
		)
		(fp_line
			(start -0.12065 -0.2794)
			(end -0.12065 -0.3048)
			(stroke
				(width 0.1)
				(type default)
			)
			(layer "B.Fab")
		)
		(fp_line
			(start -0.120396 0.2794)
			(end 0.12065 0.2794)
			(stroke
				(width 0.1)
				(type default)
			)
			(layer "B.Fab")
		)
		(fp_line
			(start -0.120396 0.3048)
			(end -0.120396 0.2794)
			(stroke
				(width 0.1)
				(type default)
			)
			(layer "B.Fab")
		)
		(fp_line
			(start 0.12065 -0.305054)
			(end 0.12065 -0.2794)
			(stroke
				(width 0.1)
				(type default)
			)
			(layer "B.Fab")
		)
		(fp_line
			(start 0.12065 -0.2794)
			(end -0.12065 -0.2794)
			(stroke
				(width 0.1)
				(type default)
			)
			(layer "B.Fab")
		)
		(fp_line
			(start 0.12065 0.2794)
			(end 0.12065 0.3048)
			(stroke
				(width 0.1)
				(type default)
			)
			(layer "B.Fab")
		)
		(fp_line
			(start 0.12065 0.3048)
			(end 0.67945 0.3048)
			(stroke
				(width 0.1)
				(type default)
			)
			(layer "B.Fab")
		)
		(fp_line
			(start 0.67945 -0.305054)
			(end 0.12065 -0.305054)
			(stroke
				(width 0.1)
				(type default)
			)
			(layer "B.Fab")
		)
		(fp_line
			(start 0.67945 0.3048)
			(end 0.67945 -0.305054)
			(stroke
				(width 0.1)
				(type default)
			)
			(layer "B.Fab")
		)
		(pad "1" smd circle
			(at 0.40005 0 180)
			(size 0 0)
			(layers "B.Cu" "B.Mask" "B.Paste")
			(net "PD_GPP_I_16")
		)
		(pad "2" smd circle
			(at -0.40005 0 180)
			(size 0 0)
			(layers "B.Cu" "B.Mask" "B.Paste")
			(net "GND")
		)
	)
)
